(kicad_pcb
	(version 20221018)
	(generator pcbnew)
	(general
    (thickness 1.562)
  )
	(paper "A4")
	(title_block
    (title "Thunderbolt PCIe Adaper")
    (date "2024-07-09")
    (rev "1.0.3")
    (comment 1 "www.antmicro.com")
    (comment 2 "Antmicro Ltd.")
		(comment 9 "footprint 10 of 271 (U4), pads 1-95 of 337")
	)
	(layers
    (0 "F.Cu" signal)
    (1 "In1.Cu" signal)
    (2 "In2.Cu" signal)
    (3 "In3.Cu" signal)
    (4 "In4.Cu" signal)
    (31 "B.Cu" signal)
    (32 "B.Adhes" user "B.Adhesive")
    (33 "F.Adhes" user "F.Adhesive")
    (34 "B.Paste" user)
    (35 "F.Paste" user)
    (36 "B.SilkS" user "B.Silkscreen")
    (37 "F.SilkS" user "F.Silkscreen")
    (38 "B.Mask" user)
    (39 "F.Mask" user)
    (40 "Dwgs.User" user "User.Drawings")
    (41 "Cmts.User" user "User.Comments")
    (42 "Eco1.User" user "User.Eco1")
    (43 "Eco2.User" user "User.Eco2")
    (44 "Edge.Cuts" user)
    (45 "Margin" user)
    (46 "B.CrtYd" user "B.Courtyard")
    (47 "F.CrtYd" user "F.Courtyard")
    (48 "B.Fab" user)
    (49 "F.Fab" user)
  )
	(footprint "antmicro-footprints:JHL6340SLLSQ"
    (layer "F.Cu")
    (at 134.8 79.85 -90)
    (property "Author" "Antmicro")
    (property "License" "Apache-2.0")
    (property "MPN" "JHL6340SLLSQ")
    (property "Manufacturer" "Intel")
    (property "Sheetfile" "tb-power.kicad_sch")
    (property "Sheetname" "Thunderbolt Controller - Power")
    (property "ki_description" "Thunderbolt™ 3 Controller, I/O")
    (property "ki_keywords" "IC")
    (attr smd)
    (fp_text reference "U4" (at -4.666 -6.17 -90 unlocked) (layer "F.SilkS")
        (effects (font (size 0.7 0.7) (thickness 0.15)))
    )
    (fp_text value "JHL6340SLLSQ" (at 0 6.4 -90 unlocked) (layer "F.Fab")
        (effects (font (size 0.7 0.7) (thickness 0.15)))
    )
    (pad "A1" smd circle (at -5.06 -5.06 270) (size 0.254 0.254) (layers "F.Cu" "F.Paste" "F.Mask")
      (net 1 "GND") (pinfunction "SVR_VSS") (pintype "power_in"))
    (pad "A2" smd oval (at -4.6 -5.06 270) (size 0.1578 0.3302) (layers "F.Cu" "F.Paste" "F.Mask")
      (net 2 "3V3_SYS") (pinfunction "VCC3P3_SVR") (pintype "power_in"))
    (pad "A3" smd oval (at -4.14 -5.06 270) (size 0.1578 0.3302) (layers "F.Cu" "F.Paste" "F.Mask")
      (net 2 "3V3_SYS") (pinfunction "VCC3P3_SVR") (pintype "passive"))
    (pad "A4" smd oval (at -3.68 -5.06 270) (size 0.1578 0.3302) (layers "F.Cu" "F.Paste" "F.Mask")
      (net 66 "LSX_P2R") (pinfunction "PA_LSRX") (pintype "input"))
    (pad "A5" smd oval (at -3.22 -5.06 270) (size 0.1578 0.3302) (layers "F.Cu" "F.Paste" "F.Mask")
      (net 67 "LSX_R2P") (pinfunction "PA_LSTX") (pintype "output"))
    (pad "A6" smd oval (at -2.76 -5.06 270) (size 0.1578 0.3302) (layers "F.Cu" "F.Paste" "F.Mask")
      (net 1 "GND") (pinfunction "VSS_ANA") (pintype "passive"))
    (pad "A7" smd oval (at -2.3 -5.06 270) (size 0.1578 0.3302) (layers "F.Cu" "F.Paste" "F.Mask")
      (net 220 "unconnected-(U4E-PB_RX1_N-PadA7)") (pinfunction "PB_RX1_N") (pintype "input+no_connect"))
    (pad "A8" smd oval (at -1.84 -5.06 270) (size 0.1578 0.3302) (layers "F.Cu" "F.Paste" "F.Mask")
      (net 1 "GND") (pinfunction "VSS_ANA") (pintype "passive"))
    (pad "A9" smd oval (at -1.38 -5.06 270) (size 0.1578 0.3302) (layers "F.Cu" "F.Paste" "F.Mask")
      (net 221 "unconnected-(U4E-PB_TX1_P-PadA9)") (pinfunction "PB_TX1_P") (pintype "output+no_connect"))
    (pad "A10" smd oval (at -0.92 -5.06 270) (size 0.1578 0.3302) (layers "F.Cu" "F.Paste" "F.Mask")
      (net 1 "GND") (pinfunction "VSS_ANA") (pintype "passive"))
    (pad "A11" smd oval (at -0.46 -5.06 270) (size 0.1578 0.3302) (layers "F.Cu" "F.Paste" "F.Mask")
      (net 222 "unconnected-(U4E-PB_TX0_P-PadA11)") (pinfunction "PB_TX0_P") (pintype "output+no_connect"))
    (pad "A12" smd oval (at 0 -5.06 270) (size 0.1578 0.3302) (layers "F.Cu" "F.Paste" "F.Mask")
      (net 1 "GND") (pinfunction "VSS_ANA") (pintype "passive"))
    (pad "A13" smd oval (at 0.46 -5.06 270) (size 0.1578 0.3302) (layers "F.Cu" "F.Paste" "F.Mask")
      (net 223 "unconnected-(U4E-PB_RX0_P-PadA13)") (pinfunction "PB_RX0_P") (pintype "input+no_connect"))
    (pad "A14" smd oval (at 0.92 -5.06 270) (size 0.1578 0.3302) (layers "F.Cu" "F.Paste" "F.Mask")
      (net 1 "GND") (pinfunction "VSS_ANA") (pintype "passive"))
    (pad "A15" smd oval (at 1.38 -5.06 270) (size 0.1578 0.3302) (layers "F.Cu" "F.Paste" "F.Mask")
      (net 37 "TB_RX1_P") (pinfunction "PA_RX1_P") (pintype "input"))
    (pad "A16" smd oval (at 1.84 -5.06 270) (size 0.1578 0.3302) (layers "F.Cu" "F.Paste" "F.Mask")
      (net 1 "GND") (pinfunction "VSS_ANA") (pintype "passive"))
    (pad "A17" smd oval (at 2.3 -5.06 270) (size 0.1578 0.3302) (layers "F.Cu" "F.Paste" "F.Mask")
      (net 15 "/TB Controller/PA_TX1_P") (pinfunction "PA_TX1_P") (pintype "output"))
    (pad "A18" smd oval (at 2.76 -5.06 270) (size 0.1578 0.3302) (layers "F.Cu" "F.Paste" "F.Mask")
      (net 1 "GND") (pinfunction "VSS_ANA") (pintype "passive"))
    (pad "A19" smd oval (at 3.22 -5.06 270) (size 0.1578 0.3302) (layers "F.Cu" "F.Paste" "F.Mask")
      (net 13 "/TB Controller/PA_TX0_P") (pinfunction "PA_TX0_P") (pintype "output"))
    (pad "A20" smd oval (at 3.68 -5.06 270) (size 0.1578 0.3302) (layers "F.Cu" "F.Paste" "F.Mask")
      (net 1 "GND") (pinfunction "VSS_ANA") (pintype "passive"))
    (pad "A21" smd oval (at 4.14 -5.06 270) (size 0.1578 0.3302) (layers "F.Cu" "F.Paste" "F.Mask")
      (net 41 "TB_RX0_N") (pinfunction "PA_RX0_N") (pintype "input"))
    (pad "A22" smd oval (at 4.6 -5.06 270) (size 0.1578 0.3302) (layers "F.Cu" "F.Paste" "F.Mask")
      (net 1 "GND") (pinfunction "VSS_ANA") (pintype "passive"))
    (pad "A23" smd circle (at 5.06 -5.06 270) (size 0.254 0.254) (layers "F.Cu" "F.Paste" "F.Mask")
      (net 224 "unconnected-(U4F-ATEST_P-PadA23)") (pinfunction "ATEST_P") (pintype "passive+no_connect"))
    (pad "AA1" smd oval (at -5.06 4.14) (size 0.1578 0.3302) (layers "F.Cu" "F.Paste" "F.Mask")
      (net 197 "Net-(U4C-GPIO_8)") (pinfunction "GPIO_8") (pintype "bidirectional"))
    (pad "AA2" smd circle (at -4.6 4.14 270) (size 0.254 0.254) (layers "F.Cu" "F.Paste" "F.Mask")
      (net 171 "Net-(U4C-DPSNK0_HPD)") (pinfunction "DPSNK0_HPD") (pintype "passive"))
    (pad "AA22" smd circle (at 4.6 4.14 270) (size 0.254 0.254) (layers "F.Cu" "F.Paste" "F.Mask")
      (net 1 "GND") (pinfunction "VSS_ANA") (pintype "passive"))
    (pad "AA23" smd oval (at 5.06 4.14) (size 0.1578 0.3302) (layers "F.Cu" "F.Paste" "F.Mask")
      (net 1 "GND") (pinfunction "VSS_ANA") (pintype "passive"))
    (pad "AB1" smd oval (at -5.06 4.6) (size 0.1578 0.3302) (layers "F.Cu" "F.Paste" "F.Mask")
      (net 1 "GND") (pinfunction "VSS") (pintype "passive"))
    (pad "AB2" smd circle (at -4.6 4.6 270) (size 0.254 0.254) (layers "F.Cu" "F.Paste" "F.Mask")
      (net 1 "GND") (pinfunction "MONDC_DPSRC") (pintype "passive"))
    (pad "AB3" smd circle (at -4.14 4.6 270) (size 0.254 0.254) (layers "F.Cu" "F.Paste" "F.Mask")
      (net 69 "SPI_MOSI") (pinfunction "EE_DI") (pintype "output"))
    (pad "AB4" smd circle (at -3.68 4.6 270) (size 0.254 0.254) (layers "F.Cu" "F.Paste" "F.Mask")
      (net 68 "SPI_SCLK") (pinfunction "EE_CLK") (pintype "output"))
    (pad "AB5" smd circle (at -3.22 4.6 270) (size 0.254 0.254) (layers "F.Cu" "F.Paste" "F.Mask")
      (net 204 "Net-(U4D-TEST_PWR_GOOD)") (pinfunction "TEST_PWR_GOOD") (pintype "input"))
    (pad "AB6" smd circle (at -2.76 4.6 270) (size 0.254 0.254) (layers "F.Cu" "F.Paste" "F.Mask")
      (net 1 "GND") (pinfunction "VSS_ANA") (pintype "passive"))
    (pad "AB7" smd circle (at -2.3 4.6 270) (size 0.254 0.254) (layers "F.Cu" "F.Paste" "F.Mask")
      (net 225 "unconnected-(U4C-DPSNK0_ML0_P-PadAB7)") (pinfunction "DPSNK0_ML0_P") (pintype "input+no_connect"))
    (pad "AB8" smd circle (at -1.84 4.6 270) (size 0.254 0.254) (layers "F.Cu" "F.Paste" "F.Mask")
      (net 1 "GND") (pinfunction "VSS_ANA") (pintype "passive"))
    (pad "AB9" smd circle (at -1.38 4.6 270) (size 0.254 0.254) (layers "F.Cu" "F.Paste" "F.Mask")
      (net 226 "unconnected-(U4C-DPSNK0_ML1_P-PadAB9)") (pinfunction "DPSNK0_ML1_P") (pintype "input+no_connect"))
    (pad "AB10" smd circle (at -0.92 4.6 270) (size 0.254 0.254) (layers "F.Cu" "F.Paste" "F.Mask")
      (net 1 "GND") (pinfunction "VSS_ANA") (pintype "passive"))
    (pad "AB11" smd circle (at -0.46 4.6 270) (size 0.254 0.254) (layers "F.Cu" "F.Paste" "F.Mask")
      (net 227 "unconnected-(U4C-DPSNK0_ML2_P-PadAB11)") (pinfunction "DPSNK0_ML2_P") (pintype "input+no_connect"))
    (pad "AB12" smd circle (at 0 4.6 270) (size 0.254 0.254) (layers "F.Cu" "F.Paste" "F.Mask")
      (net 1 "GND") (pinfunction "VSS_ANA") (pintype "passive"))
    (pad "AB13" smd circle (at 0.46 4.6 270) (size 0.254 0.254) (layers "F.Cu" "F.Paste" "F.Mask")
      (net 228 "unconnected-(U4C-DPSNK0_ML3_P-PadAB13)") (pinfunction "DPSNK0_ML3_P") (pintype "input+no_connect"))
    (pad "AB14" smd circle (at 0.92 4.6 270) (size 0.254 0.254) (layers "F.Cu" "F.Paste" "F.Mask")
      (net 1 "GND") (pinfunction "VSS_ANA") (pintype "passive"))
    (pad "AB15" smd circle (at 1.38 4.6 270) (size 0.254 0.254) (layers "F.Cu" "F.Paste" "F.Mask")
      (net 229 "unconnected-(U4C-DPSNK1_ML0_P-PadAB15)") (pinfunction "DPSNK1_ML0_P") (pintype "input+no_connect"))
    (pad "AB16" smd circle (at 1.84 4.6 270) (size 0.254 0.254) (layers "F.Cu" "F.Paste" "F.Mask")
      (net 1 "GND") (pinfunction "VSS_ANA") (pintype "passive"))
    (pad "AB17" smd circle (at 2.3 4.6 270) (size 0.254 0.254) (layers "F.Cu" "F.Paste" "F.Mask")
      (net 230 "unconnected-(U4C-DPSNK1_ML1_P-PadAB17)") (pinfunction "DPSNK1_ML1_P") (pintype "input+no_connect"))
    (pad "AB18" smd circle (at 2.76 4.6 270) (size 0.254 0.254) (layers "F.Cu" "F.Paste" "F.Mask")
      (net 1 "GND") (pinfunction "VSS_ANA") (pintype "passive"))
    (pad "AB19" smd circle (at 3.22 4.6 270) (size 0.254 0.254) (layers "F.Cu" "F.Paste" "F.Mask")
      (net 231 "unconnected-(U4C-DPSNK1_ML2_P-PadAB19)") (pinfunction "DPSNK1_ML2_P") (pintype "input+no_connect"))
    (pad "AB20" smd circle (at 3.68 4.6 270) (size 0.254 0.254) (layers "F.Cu" "F.Paste" "F.Mask")
      (net 1 "GND") (pinfunction "VSS_ANA") (pintype "passive"))
    (pad "AB21" smd circle (at 4.14 4.6 270) (size 0.254 0.254) (layers "F.Cu" "F.Paste" "F.Mask")
      (net 232 "unconnected-(U4C-DPSNK1_ML3_P-PadAB21)") (pinfunction "DPSNK1_ML3_P") (pintype "input+no_connect"))
    (pad "AB22" smd circle (at 4.6 4.6 270) (size 0.254 0.254) (layers "F.Cu" "F.Paste" "F.Mask")
      (net 1 "GND") (pinfunction "VSS_ANA") (pintype "passive"))
    (pad "AB23" smd oval (at 5.06 4.6) (size 0.1578 0.3302) (layers "F.Cu" "F.Paste" "F.Mask")
      (net 233 "unconnected-(U4F-THERMDA2-PadAB23)") (pinfunction "THERMDA2") (pintype "passive+no_connect"))
    (pad "AC1" smd circle (at -5.06 5.06 270) (size 0.254 0.254) (layers "F.Cu" "F.Paste" "F.Mask")
      (net 1 "GND") (pinfunction "TEST_EDM") (pintype "passive"))
    (pad "AC2" smd oval (at -4.6 5.06 270) (size 0.1578 0.3302) (layers "F.Cu" "F.Paste" "F.Mask")
      (net 1 "GND") (pinfunction "VSS") (pintype "passive"))
    (pad "AC3" smd oval (at -4.14 5.06 270) (size 0.1578 0.3302) (layers "F.Cu" "F.Paste" "F.Mask")
      (net 65 "SPI_CS") (pinfunction "EE_CS_N") (pintype "output"))
    (pad "AC4" smd oval (at -3.68 5.06 270) (size 0.1578 0.3302) (layers "F.Cu" "F.Paste" "F.Mask")
      (net 63 "SPI_MISO") (pinfunction "EE_D0") (pintype "input"))
    (pad "AC5" smd oval (at -3.22 5.06 270) (size 0.1578 0.3302) (layers "F.Cu" "F.Paste" "F.Mask")
      (net 170 "Net-(U4B-PCIE_CLKREQ_N)") (pinfunction "PCIE_CLKREQ_N") (pintype "output"))
    (pad "AC6" smd oval (at -2.76 5.06 270) (size 0.1578 0.3302) (layers "F.Cu" "F.Paste" "F.Mask")
      (net 1 "GND") (pinfunction "VSS_ANA") (pintype "passive"))
    (pad "AC7" smd oval (at -2.3 5.06 270) (size 0.1578 0.3302) (layers "F.Cu" "F.Paste" "F.Mask")
      (net 234 "unconnected-(U4C-DPSNK0_ML0_N-PadAC7)") (pinfunction "DPSNK0_ML0_N") (pintype "input+no_connect"))
    (pad "AC8" smd oval (at -1.84 5.06 270) (size 0.1578 0.3302) (layers "F.Cu" "F.Paste" "F.Mask")
      (net 1 "GND") (pinfunction "VSS_ANA") (pintype "passive"))
    (pad "AC9" smd oval (at -1.38 5.06 270) (size 0.1578 0.3302) (layers "F.Cu" "F.Paste" "F.Mask")
      (net 235 "unconnected-(U4C-DPSNK0_ML1_N-PadAC9)") (pinfunction "DPSNK0_ML1_N") (pintype "input+no_connect"))
    (pad "AC10" smd oval (at -0.92 5.06 270) (size 0.1578 0.3302) (layers "F.Cu" "F.Paste" "F.Mask")
      (net 1 "GND") (pinfunction "VSS_ANA") (pintype "passive"))
    (pad "AC11" smd oval (at -0.46 5.06 270) (size 0.1578 0.3302) (layers "F.Cu" "F.Paste" "F.Mask")
      (net 236 "unconnected-(U4C-DPSNK0_ML2_N-PadAC11)") (pinfunction "DPSNK0_ML2_N") (pintype "input+no_connect"))
    (pad "AC12" smd oval (at 0 5.06 270) (size 0.1578 0.3302) (layers "F.Cu" "F.Paste" "F.Mask")
      (net 1 "GND") (pinfunction "VSS_ANA") (pintype "passive"))
    (pad "AC13" smd oval (at 0.46 5.06 270) (size 0.1578 0.3302) (layers "F.Cu" "F.Paste" "F.Mask")
      (net 237 "unconnected-(U4C-DPSNK0_ML3_N-PadAC13)") (pinfunction "DPSNK0_ML3_N") (pintype "input+no_connect"))
    (pad "AC14" smd oval (at 0.92 5.06 270) (size 0.1578 0.3302) (layers "F.Cu" "F.Paste" "F.Mask")
      (net 1 "GND") (pinfunction "VSS_ANA") (pintype "passive"))
    (pad "AC15" smd oval (at 1.38 5.06 270) (size 0.1578 0.3302) (layers "F.Cu" "F.Paste" "F.Mask")
      (net 238 "unconnected-(U4C-DPSNK1_ML0_N-PadAC15)") (pinfunction "DPSNK1_ML0_N") (pintype "input+no_connect"))
    (pad "AC16" smd oval (at 1.84 5.06 270) (size 0.1578 0.3302) (layers "F.Cu" "F.Paste" "F.Mask")
      (net 1 "GND") (pinfunction "VSS_ANA") (pintype "passive"))
    (pad "AC17" smd oval (at 2.3 5.06 270) (size 0.1578 0.3302) (layers "F.Cu" "F.Paste" "F.Mask")
      (net 239 "unconnected-(U4C-DPSNK1_ML1_N-PadAC17)") (pinfunction "DPSNK1_ML1_N") (pintype "input+no_connect"))
    (pad "AC18" smd oval (at 2.76 5.06 270) (size 0.1578 0.3302) (layers "F.Cu" "F.Paste" "F.Mask")
      (net 1 "GND") (pinfunction "VSS_ANA") (pintype "passive"))
    (pad "AC19" smd oval (at 3.22 5.06 270) (size 0.1578 0.3302) (layers "F.Cu" "F.Paste" "F.Mask")
      (net 240 "unconnected-(U4C-DPSNK1_ML2_N-PadAC19)") (pinfunction "DPSNK1_ML2_N") (pintype "input+no_connect"))
    (pad "AC20" smd oval (at 3.68 5.06 270) (size 0.1578 0.3302) (layers "F.Cu" "F.Paste" "F.Mask")
      (net 1 "GND") (pinfunction "VSS_ANA") (pintype "passive"))
    (pad "AC21" smd oval (at 4.14 5.06 270) (size 0.1578 0.3302) (layers "F.Cu" "F.Paste" "F.Mask")
      (net 241 "unconnected-(U4C-DPSNK1_ML3_N-PadAC21)") (pinfunction "DPSNK1_ML3_N") (pintype "input+no_connect"))
    (pad "AC22" smd oval (at 4.6 5.06 270) (size 0.1578 0.3302) (layers "F.Cu" "F.Paste" "F.Mask")
      (net 1 "GND") (pinfunction "VSS_ANA") (pintype "passive"))
    (pad "AC23" smd circle (at 5.06 5.06 270) (size 0.254 0.254) (layers "F.Cu" "F.Paste" "F.Mask")
      (net 242 "unconnected-(U4F-THERMDA1-PadAC23)") (pinfunction "THERMDA1") (pintype "passive+no_connect"))
    (pad "B1" smd oval (at -5.06 -4.6) (size 0.1578 0.3302) (layers "F.Cu" "F.Paste" "F.Mask")
      (net 1 "GND") (pinfunction "SVR_VSS") (pintype "passive"))
    (pad "B2" smd circle (at -4.6 -4.6 270) (size 0.254 0.254) (layers "F.Cu" "F.Paste" "F.Mask")
      (net 1 "GND") (pinfunction "SVR_VSS") (pintype "passive"))
    (pad "B3" smd circle (at -4.14 -4.6 270) (size 0.254 0.254) (layers "F.Cu" "F.Paste" "F.Mask")
      (net 2 "3V3_SYS") (pinfunction "VCC3P3_SVR") (pintype "passive"))
    (pad "B4" smd circle (at -3.68 -4.6 270) (size 0.254 0.254) (layers "F.Cu" "F.Paste" "F.Mask")
      (net 185 "Net-(U4E-PB_LSTX)") (pinfunction "PB_LSTX") (pintype "output"))
    (pad "B5" smd circle (at -3.22 -4.6 270) (size 0.254 0.254) (layers "F.Cu" "F.Paste" "F.Mask")
      (net 186 "Net-(U4E-PB_LSRX)") (pinfunction "PB_LSRX") (pintype "input"))
    (pad "B6" smd circle (at -2.76 -4.6 270) (size 0.254 0.254) (layers "F.Cu" "F.Paste" "F.Mask")
      (net 1 "GND") (pinfunction "VSS_ANA") (pintype "passive"))
    (pad "B7" smd circle (at -2.3 -4.6 270) (size 0.254 0.254) (layers "F.Cu" "F.Paste" "F.Mask")
      (net 243 "unconnected-(U4E-PB_RX1_P-PadB7)") (pinfunction "PB_RX1_P") (pintype "input+no_connect"))
    (pad "B8" smd circle (at -1.84 -4.6 270) (size 0.254 0.254) (layers "F.Cu" "F.Paste" "F.Mask")
      (net 1 "GND") (pinfunction "VSS_ANA") (pintype "passive"))
    (pad "B9" smd circle (at -1.38 -4.6 270) (size 0.254 0.254) (layers "F.Cu" "F.Paste" "F.Mask")
      (net 244 "unconnected-(U4E-PB_TX1_N-PadB9)") (pinfunction "PB_TX1_N") (pintype "output+no_connect"))
    (pad "B10" smd circle (at -0.92 -4.6 270) (size 0.254 0.254) (layers "F.Cu" "F.Paste" "F.Mask")
      (net 1 "GND") (pinfunction "VSS_ANA") (pintype "passive"))
    (pad "B11" smd circle (at -0.46 -4.6 270) (size 0.254 0.254) (layers "F.Cu" "F.Paste" "F.Mask")
      (net 245 "unconnected-(U4E-PB_TX0_N-PadB11)") (pinfunction "PB_TX0_N") (pintype "output+no_connect"))
    (pad "B12" smd circle (at 0 -4.6 270) (size 0.254 0.254) (layers "F.Cu" "F.Paste" "F.Mask")
      (net 1 "GND") (pinfunction "VSS_ANA") (pintype "passive"))
    (pad "B13" smd circle (at 0.46 -4.6 270) (size 0.254 0.254) (layers "F.Cu" "F.Paste" "F.Mask")
      (net 246 "unconnected-(U4E-PB_RX0_N-PadB13)") (pinfunction "PB_RX0_N") (pintype "input+no_connect"))
    (pad "B14" smd circle (at 0.92 -4.6 270) (size 0.254 0.254) (layers "F.Cu" "F.Paste" "F.Mask")
      (net 1 "GND") (pinfunction "VSS_ANA") (pintype "passive"))
    (pad "B15" smd circle (at 1.38 -4.6 270) (size 0.254 0.254) (layers "F.Cu" "F.Paste" "F.Mask")
      (net 36 "TB_RX1_N") (pinfunction "PA_RX1_N") (pintype "input"))
    (pad "B16" smd circle (at 1.84 -4.6 270) (size 0.254 0.254) (layers "F.Cu" "F.Paste" "F.Mask")
      (net 1 "GND") (pinfunction "VSS_ANA") (pintype "passive"))
    (pad "B17" smd circle (at 2.3 -4.6 270) (size 0.254 0.254) (layers "F.Cu" "F.Paste" "F.Mask")
      (net 22 "/TB Controller/PA_TX1_N") (pinfunction "PA_TX1_N") (pintype "output"))
    (pad "B18" smd circle (at 2.76 -4.6 270) (size 0.254 0.254) (layers "F.Cu" "F.Paste" "F.Mask")
      (net 1 "GND") (pinfunction "VSS_ANA") (pintype "passive"))
    (pad "B19" smd circle (at 3.22 -4.6 270) (size 0.254 0.254) (layers "F.Cu" "F.Paste" "F.Mask")
      (net 18 "/TB Controller/PA_TX0_N") (pinfunction "PA_TX0_N") (pintype "output"))
    (pad "B20" smd circle (at 3.68 -4.6 270) (size 0.254 0.254) (layers "F.Cu" "F.Paste" "F.Mask")
      (net 1 "GND") (pinfunction "VSS_ANA") (pintype "passive"))
    (pad "B21" smd circle (at 4.14 -4.6 270) (size 0.254 0.254) (layers "F.Cu" "F.Paste" "F.Mask")
      (net 42 "TB_RX0_P") (pinfunction "PA_RX0_P") (pintype "input"))
    (pad "B22" smd circle (at 4.6 -4.6 270) (size 0.254 0.254) (layers "F.Cu" "F.Paste" "F.Mask")
      (net 1 "GND") (pinfunction "VSS_ANA") (pintype "passive"))
  )
)
